# TIMECARD (Time Appliance Project (Time Card)) — schematic netlist excerpt (pin names and nets, part order shuffled) for the footprints in the layout excerpt that follows; sources: Cadence DE-HDL packaged netlist, KiCad conversion of R4006-B0001-02_R01.brd

C134  CAPACITOR  0.1UF 10V 10%  pkg SMC_0402R_H022  page 14 : \1\ = XP3R3V_FPGA ; \2\ = SG
R330  RESISTOR  33OHM 1%  pkg SMC_0402R_H016  page 20 : \1\ = R_BNO080_EVN_SDA ; \2\ = BNO080_EVN_SDA

(kicad_pcb
	(version 20260206)
	(generator "pcbnew")
	(generator_version "10.0")
	(general
		(thickness 1.6)
		(legacy_teardrops no)
	)
	(paper "A4")
	(title_block
		(title "timecard-production-celestica-r4006 — R4006-B0001-02_R01.brd")
		(comment 1 "Time Appliance Project (Time Card) / footprints 859-860 of 1113")
	)
	(layers
		(0 "F.Cu" signal "TOP")
		(4 "In1.Cu" signal "L02_GND1")
		(6 "In2.Cu" signal "L03_SIG1")
		(8 "In3.Cu" signal "L04_GND2")
		(10 "In4.Cu" signal "L05_VCC1")
		(12 "In5.Cu" signal "L06_VCC2")
		(14 "In6.Cu" signal "L07_GND3")
		(16 "In7.Cu" signal "L08_SIG2")
		(18 "In8.Cu" signal "L09_GND4")
		(2 "B.Cu" signal "BOTTOM")
		(9 "F.Adhes" user "F.Adhesive")
		(11 "B.Adhes" user "B.Adhesive")
		(13 "F.Paste" user "Package Geometry/Pastemask Top")
		(15 "B.Paste" user "Package Geometry/Pastemask Bottom")
		(5 "F.SilkS" user "Ref Des/Silkscreen Top")
		(7 "B.SilkS" user "Ref Des/Silkscreen Bottom")
		(1 "F.Mask" user "Board Geometry/Soldermask Top")
		(3 "B.Mask" user "Board Geometry/Soldermask Bottom")
		(17 "Dwgs.User" user "User.Drawings")
		(19 "Cmts.User" user "User.Comments")
		(21 "Eco1.User" user "User.Eco1")
		(23 "Eco2.User" user "User.Eco2")
		(25 "Edge.Cuts" user "Board Geometry/Outline")
		(27 "Margin" user)
		(31 "F.CrtYd" user "Package Geometry/Place Bound Top")
		(29 "B.CrtYd" user "Package Geometry/Place Bound Bottom")
		(35 "F.Fab" user "Ref Des/Assembly Top")
		(33 "B.Fab" user "Ref Des/Assembly Bottom")
	)
	(footprint ""
		(layer "B.Cu")
		(at 87.376 -73.279 90)
		(property "Reference" "R330"
			(at -3.556 -0.16637 270)
			(unlocked yes)
			(layer "B.SilkS")
			(effects
				(font
					(size 0.7874 0.5842)
					(thickness 0.1524)
				)
				(justify mirror)
			)
		)
		(property "Value" "VAL*"
			(at -0.02032 2.13233 90)
			(unlocked yes)
			(layer "B.Fab")
			(hide yes)
			(effects
				(font
					(size 0.7874 0.5842)
					(thickness 0.1524)
				)
				(justify mirror)
			)
		)
		(property "Device Type" "RESISTOR-G155-133R0-01,33OHM,1%"
			(at -0.008382 1.210564 90)
			(unlocked yes)
			(layer "B.Fab")
			(hide yes)
			(effects
				(font
					(size 0.7874 0.5842)
					(thickness 0.1524)
				)
				(justify mirror)
			)
		)
		(property "User Part Number" "PARTNUM*"
			(at -0.02032 4.024884 90)
			(unlocked yes)
			(layer "Cmts.User")
			(hide yes)
			(effects
				(font
					(size 0.7874 0.5842)
					(thickness 0.1524)
				)
				(justify mirror)
			)
		)
		(property "Tolerance" "TOL*"
			(at -0.044704 3.05435 90)
			(unlocked yes)
			(layer "Cmts.User")
			(hide yes)
			(effects
				(font
					(size 0.7874 0.5842)
					(thickness 0.1524)
				)
				(justify mirror)
			)
		)
		(duplicate_pad_numbers_are_jumpers no)
		(fp_line
			(start 1.143 -0.5588)
			(end 1.143 0.5588)
			(stroke
				(width 0.1)
				(type default)
			)
			(layer "B.SilkS")
		)
		(fp_line
			(start -1.143 -0.5588)
			(end 1.143 -0.5588)
			(stroke
				(width 0.1)
				(type default)
			)
			(layer "B.SilkS")
		)
		(fp_line
			(start 1.143 0.5588)
			(end -1.143 0.5588)
			(stroke
				(width 0.1)
				(type default)
			)
			(layer "B.SilkS")
		)
		(fp_line
			(start -1.143 0.5588)
			(end -1.143 -0.5588)
			(stroke
				(width 0.1)
				(type default)
			)
			(layer "B.SilkS")
		)
		(fp_rect
			(start 1.143 -0.5588)
			(end -1.143 0.5588)
			(stroke
				(width 0)
				(type default)
			)
			(fill no)
			(layer "B.CrtYd")
		)
		(fp_line
			(start 0.508 -0.3048)
			(end 0.508 0.3048)
			(stroke
				(width 0.1)
				(type default)
			)
			(layer "B.Fab")
		)
		(fp_line
			(start -0.508 -0.3048)
			(end 0.508 -0.3048)
			(stroke
				(width 0.1)
				(type default)
			)
			(layer "B.Fab")
		)
		(fp_line
			(start 0.508 0.3048)
			(end -0.508 0.3048)
			(stroke
				(width 0.1)
				(type default)
			)
			(layer "B.Fab")
		)
		(fp_line
			(start -0.508 0.3048)
			(end -0.508 -0.3048)
			(stroke
				(width 0.1)
				(type default)
			)
			(layer "B.Fab")
		)
		(pad "1" smd rect
			(at 0.5334 0 270)
			(size 0.7112 0.6096)
			(layers "B.Cu" "B.Mask" "B.Paste")
			(net "R_BNO080_EVN_SDA")
		)
		(pad "2" smd rect
			(at -0.5334 0 270)
			(size 0.7112 0.6096)
			(layers "B.Cu" "B.Mask" "B.Paste")
			(net "BNO080_EVN_SDA")
		)
		(zone
			(layer "B.Cu")
			(hatch none 0.5)
			(connect_pads
				(clearance 0)
			)
			(min_thickness 0.25)
			(keepout
				(tracks allowed)
				(vias not_allowed)
				(pads allowed)
				(copperpour not_allowed)
				(footprints allowed)
			)
			(placement
				(enabled no)
				(sheetname "")
			)
			(fill
				(thermal_gap 0.5)
				(thermal_bridge_width 0.5)
				(island_removal_mode 0)
			)
			(polygon
				(pts
					(xy 87.0712 -73.3552) (xy 87.0712 -73.2028) (xy 87.6808 -73.2028) (xy 87.6808 -73.3552)
				)
			)
		)
	)
	(footprint ""
		(layer "B.Cu")
		(at 114.34699 -52.82311)
		(property "Reference" "C134"
			(at -0.04699 -1.12014 0)
			(unlocked yes)
			(layer "B.SilkS")
			(effects
				(font
					(size 0.635 0.4064)
					(thickness 0.1524)
				)
				(justify mirror)
			)
		)
		(property "Value" "VAL*"
			(at 0 3.718306 0)
			(unlocked yes)
			(layer "B.Fab")
			(hide yes)
			(effects
				(font
					(size 0.7874 0.5842)
					(thickness 0.127)
				)
				(justify mirror)
			)
		)
		(property "Tolerance" "TOL*"
			(at 0 4.861306 0)
			(unlocked yes)
			(layer "Cmts.User")
			(hide yes)
			(effects
				(font
					(size 0.7874 0.5842)
					(thickness 0.127)
				)
				(justify mirror)
			)
		)
		(property "User Part Number" "PARTNUM*"
			(at 0 2.575306 0)
			(unlocked yes)
			(layer "Cmts.User")
			(hide yes)
			(effects
				(font
					(size 0.7874 0.5842)
					(thickness 0.127)
				)
				(justify mirror)
			)
		)
		(property "Device Type" "CAPACITOR-G105-0B104-CK,0.1UF,A"
			(at 0 1.432306 0)
			(unlocked yes)
			(layer "B.Fab")
			(hide yes)
			(effects
				(font
					(size 0.7874 0.5842)
					(thickness 0.127)
				)
				(justify mirror)
			)
		)
		(duplicate_pad_numbers_are_jumpers no)
		(fp_line
			(start -0.970026 -0.4699)
			(end -0.970026 0.4699)
			(stroke
				(width 0.1)
				(type default)
			)
			(layer "B.SilkS")
		)
		(fp_line
			(start -0.970026 0.4699)
			(end 0.970026 0.4699)
			(stroke
				(width 0.1)
				(type default)
			)
			(layer "B.SilkS")
		)
		(fp_line
			(start 0.970026 -0.4699)
			(end -0.970026 -0.4699)
			(stroke
				(width 0.1)
				(type default)
			)
			(layer "B.SilkS")
		)
		(fp_line
			(start 0.970026 0.4699)
			(end 0.970026 -0.4699)
			(stroke
				(width 0.1)
				(type default)
			)
			(layer "B.SilkS")
		)
		(fp_poly
			(pts
				(xy 0.970026 0.4699) (xy -0.970026 0.4699) (xy -0.970026 -0.4699) (xy 0.970026 -0.4699)
			)
			(stroke
				(width 0)
				(type default)
			)
			(fill no)
			(layer "B.CrtYd")
		)
		(fp_line
			(start -0.508 -0.3048)
			(end -0.508 0.3048)
			(stroke
				(width 0.1)
				(type default)
			)
			(layer "B.Fab")
		)
		(fp_line
			(start -0.508 0.3048)
			(end 0.508 0.3048)
			(stroke
				(width 0.1)
				(type default)
			)
			(layer "B.Fab")
		)
		(fp_line
			(start 0.508 -0.3048)
			(end -0.508 -0.3048)
			(stroke
				(width 0.1)
				(type default)
			)
			(layer "B.Fab")
		)
		(fp_line
			(start 0.508 0.3048)
			(end 0.508 -0.3048)
			(stroke
				(width 0.1)
				(type default)
			)
			(layer "B.Fab")
		)
		(pad "1" smd circle
			(at 0.500126 0 180)
			(size 0.635 0.635)
			(layers "B.Cu" "B.Mask" "B.Paste")
			(net "XP3R3V_FPGA")
		)
		(pad "2" smd circle
			(at -0.500126 0 180)
			(size 0.635 0.635)
			(layers "B.Cu" "B.Mask" "B.Paste")
			(net "SG")
		)
	)
)
